FILE_TYPE = CONNECTIVITY;
{Allegro Design Entry HDL 17.2-2016 S081 (4005846) 1/11/2022}
"PAGE_NUMBER" = 151;
0"NC";
1"P3V3_AUX\g";
2"P3V3_AUX\g"$PHYS_NET_NAME"P3V3_AUX"CDS_PHYS_NET_NAME"P3V3_AUX"VOLTAGE"3.3"$PHYS_NET_NAME"P3V3_AUX"CDS_PHYS_NET_NAME"P3V3_AUX"VOLTAGE"3.3";
3"P3V3_AUX\g"$PHYS_NET_NAME"P3V3_AUX"CDS_PHYS_NET_NAME"P3V3_AUX"VOLTAGE"3.3"$PHYS_NET_NAME"P3V3_AUX"CDS_PHYS_NET_NAME"P3V3_AUX"VOLTAGE"3.3";
4"P3V3_AUX\g";
5"GND\g";
6"GND\g";
7"GND\g";
8"GND\g"CDS_PHYS_NET_NAME"GND"VOLTAGE"0";
9"GND\g";
10"GND\g"CDS_PHYS_NET_NAME"GND"VOLTAGE"0";
11"GND\g";
12"GND\g";
13"GND\g";
14"GND\g";
15"GND\g";
16"GND\g";
17"FB_BMC_ISOLATE";
18"FB_BMC_ISOLATE_R1";
19"OCP_SFF_AUX_PWR_EN_R4"CDS_PHYS_NET_NAME"OCP_SFF_AUX_PWR_EN_R4";
20"OCP_SFF_AUX_PWR_EN"CDS_PHYS_NET_NAME"OCP_SFF_AUX_PWR_EN";
21"OCP_SFF_AUX_PWR_EN"CDS_PHYS_NET_NAME"OCP_SFF_AUX_PWR_EN";
22"OCP_SFF_AUX_PWR_EN_R1";
23"FM_NCSI_OCP_V3_1_R_OE";
24"NCSI_OCP_SFF_TX_EN";
25"OCP_SFF_ISO2_RBT_ARB_OUT";
26"RMII_OCP_BMC_CRSDV";
27"OCP_SFF_RBT_ARB_OUT";
28"RMII_BMC_OCP_TXD_0";
29"OCP_SFF_RBT_ARB_IN";
30"OCP_SFF_RBT_ARB_IN_R"CDS_PHYS_NET_NAME"OCP_SFF_RBT_ARB_IN_R";
31"NCSI_BMC_TXD1_R";
32"FM_OCP_SFF_PWR_GOOD"CDS_PHYS_NET_NAME"FM_OCP_SFF_PWR_GOOD";
33"NCSI_OCP_SFF_RXD1";
34"NCSI_OCP_SFF_TXD1";
35"RST_HP_OCP_SFF_R_N";
36"RST_SMB_SWITCH_N"CDS_PHYS_NET_NAME"RST_SMB_SWITCH_N";
37"RMII_BMC_OCP_TX_EN";
38"RMII_BMC_OCP_TXD_1";
39"RMII_OCP_BMC_RXD_1";
40"RMII_OCP_BMC_CRSDV";
41"RMII_OCP_BMC_RXD_0";
42"RMII_OCP_BMC_RXD_0";
43"RMII_OCP_BMC_RXD_1";
44"NCSI_BMC_CRS_DV_R"CDS_PHYS_NET_NAME"NCSI_BMC_CRS_DV_R";
45"NCSI_BMC_RXD0_R"CDS_PHYS_NET_NAME"NCSI_BMC_RXD0_R";
46"NCSI_BMC_RXD1_R";
47"NCSI_BMC_TXD0_R";
48"NCSI_BMC_TX_EN_R";
49"OCP_SFF_ISO_BIF1_EN"CDS_PHYS_NET_NAME"OCP_SFF_ISO_BIF1_EN";
50"OCP_SFF_ISO_BIF2_EN"CDS_PHYS_NET_NAME"OCP_SFF_ISO_BIF2_EN";
51"RMII_BMC_OCP_TX_EN";
52"RMII_BMC_OCP_TXD_1";
53"RMII_BMC_OCP_TXD_0";
54"RMII_BMC_OCP_RX_ER";
55"OCP_SFF_ISO_BIF0_EN"CDS_PHYS_NET_NAME"OCP_SFF_ISO_BIF0_EN";
56"RST_SMB_OCP_SFF_N";
57"NCSI_OCP_SFF_RXD0"CDS_PHYS_NET_NAME"NCSI_OCP_SFF_RXD0";
58"OCP_SFF_ISO1_RBT_ARB_IN"CDS_PHYS_NET_NAME"OCP_SFF_ISO1_RBT_ARB_IN";
59"NCSI_OCP_SFF_CRS_DV"CDS_PHYS_NET_NAME"NCSI_OCP_SFF_CRS_DV";
60"NCSI_OCP_SFF_TXD0";
%"UNIVERSAL_GND"
"1","(-3375,1625)","0","logical_power","I11";
;
CDS_LIB"logical_power"
HDL_POWER"GND";
"A"14;
%"UNIVERSAL_GND"
"1","(-2525,1550)","0","logical_power","I12";
;
CDS_LIB"logical_power"
HDL_POWER"GND";
"A"13;
%"Q_RES"
"2","(-2525,1775)","0","pure_quanta","I13";
;
PART_NUMBER"CS41002FB09"
PACK_TYPE"0402LF"
TOLERANCE"1%"
WATTAGE"1/16W"
MATERIAL"CHIP"
VALUE"100K"
$LOCATION"R3232"
CDS_LIB"pure_quanta"
CDS_LOCATION"R3232"
$SEC"1"
CDS_SEC"1";
"A"
$PN"1"35;
"B"
$PN"2"13;
%"74LVC1G126SE7"
"1","(-3050,3725)","0","pure_quanta","I15";
;
PART_NUMBER"AL1G0126009"
PART_TYPE"SMLF"
MATERIAL"IC"
VALUE"74LVC1G126SE-7"
LOCATION"U66"
NEEDS_NO_SIZE"TRUE"
SEC_TYPE""
CDS_LMAN_SYM_OUTLINE"-100,100,100,-100"
CDS_LIB"pure_quanta"
SEC"1";
"OE"
$PN"1"22;
"GND"
$PN"3"12;
"VCC"
$PN"5"4;
"Y"
$PN"4"18;
"A"
$PN"2"32;
%"UNIVERSAL_GND"
"1","(-3050,3350)","0","logical_power","I16";
;
CDS_LIB"logical_power"
HDL_POWER"GND";
"A"12;
%"Q_RES"
"1","(-2200,2000)","0","pure_quanta","I17";
;
PART_NUMBER"CS00002JB13"
PACK_TYPE"0402LF"
MATERIAL"CHIP"
VALUE"0"
TOLERANCE"5%"
WATTAGE"1/16W"
$LOCATION"R3233"
CDS_LIB"pure_quanta"
CDS_LOCATION"R3233"
$SEC"1"
CDS_SEC"1";
"B"
$PN"2"56;
"A"
$PN"1"35;
%"Q_RES"
"1","(-1900,3200)","0","pure_quanta","I19";
;
PART_NUMBER"CS00002JB13"
VALUE"0"
TOLERANCE"5%"
WATTAGE"1/16W"
MATERIAL"EMPTY"
PACK_TYPE"0402LF"
$LOCATION"R2474"
CDS_LIB"pure_quanta"
CDS_LOCATION"R2474"
$SEC"1"
CDS_SEC"1";
"B"
$PN"2"17;
"A"
$PN"1"23;
%"UNIVERSAL_GND"
"1","(-1475,3300)","0","logical_power","I20";
;
HDL_POWER"GND"
CDS_LIB"logical_power";
"A"16;
%"Q_RES"
"2","(-1475,3525)","0","pure_quanta","I21";
;
PART_NUMBER"CS41002FB09"
MATERIAL"CHIP"
PACK_TYPE"0402LF"
VALUE"100K"
TOLERANCE"1%"
WATTAGE"1/16W"
$LOCATION"R1289"
CDS_LIB"pure_quanta"
CDS_LOCATION"R1289"
$SEC"1"
CDS_SEC"1";
"A"
$PN"1"17;
"B"
$PN"2"16;
%"Q_CAP"
"1","(-3475,4150)","2","pure_quanta","I22";
;
PART_NUMBER"CH4104K1B00"
PACK_TYPE"0402"
TOLERANCE"10%"
VOLTAGE"25V"
VALUE"0.1UF"
MATERIAL"X7R"
$LOCATION"C639"
CDS_LIB"pure_quanta"
CDS_LOCATION"C639"
$SEC"1"
CDS_SEC"1";
"B"
$PN"2"11;
"A"
$PN"1"4;
%"UNIVERSAL_GND"
"1","(-3475,3925)","0","logical_power","I23";
;
CDS_LIB"logical_power"
HDL_POWER"GND";
"A"11;
%"UNIVERSAL_POWER"
"1","(-3475,4375)","0","logical_power","I24";
;
HDL_POWER"P3V3_AUX"
CDS_LIB"logical_power";
"A"4;
%"UNIVERSAL_GND"
"1","(-2175,4575)","0","logical_power","I29";
;
CDS_LIB"logical_power"
HDL_POWER"GND";
"A"10;
%"Q_RES"
"1","(-4750,1950)","0","pure_quanta","I3";
;
PART_NUMBER"CS03322FB03"
WATTAGE"1/16W"
MATERIAL"CHIP"
PACK_TYPE"0402LF"
VALUE"33.2"
TOLERANCE"1%"
$LOCATION"R3231"
CDS_LIB"pure_quanta"
CDS_LOCATION"R3231"
$SEC"1"
CDS_SEC"1";
"B"
$PN"2"19;
"A"
$PN"1"20;
%"74CBTLV3126PW"
"1","(-1625,5000)","2","pure_quanta","I30";
;
PART_NUMBER"AL003126K08"
VALUE"74CBTLV3126PW"
MATERIAL"IC"
PART_TYPE"SMLF"
$LOCATION"U68"
CDS_LIB"pure_quanta"
NEEDS_NO_SIZE"TRUE"
CDS_LMAN_SYM_OUTLINE"-250,350,250,-350"
CDS_LOCATION"U68"
$SEC"1"
CDS_SEC"1";
"VCC"
$PN"14"3;
"4OE"
$PN"13"17;
"4A"
$PN"12"27;
"4B"
$PN"11"25;
"3OE"
$PN"10"17;
"3A"
$PN"9"48;
"GND"
$PN"7"10;
"1A"
$PN"2"31;
"2B"
$PN"6"60;
"1B"
$PN"3"34;
"2OE"
$PN"4"17;
"1OE"
$PN"1"17;
"3B"
$PN"8"24;
"2A"
$PN"5"47;
%"UNIVERSAL_GND"
"1","(-2375,5300)","0","logical_power","I31";
;
HDL_POWER"GND"
CDS_LIB"logical_power";
"A"9;
%"Q_CAP"
"1","(-2375,5525)","2","pure_quanta","I32";
;
PART_NUMBER"CH4104K1B00"
TOLERANCE"10%"
PACK_TYPE"0402"
MATERIAL"X7R"
VOLTAGE"25V"
VALUE"0.1UF"
$LOCATION"C641"
CDS_LIB"pure_quanta"
CDS_LOCATION"C641"
$SEC"1"
CDS_SEC"1";
"B"
$PN"2"9;
"A"
$PN"1"3;
%"UNIVERSAL_POWER"
"1","(-2175,5850)","0","logical_power","I33";
;
HDL_POWER"P3V3_AUX"
CDS_LIB"logical_power";
"A"3;
%"UNIVERSAL_GND"
"1","(-2175,6000)","0","logical_power","I38";
;
HDL_POWER"GND"
CDS_LIB"logical_power";
"A"8;
%"74CBTLV3126PW"
"1","(-1625,6425)","2","pure_quanta","I39";
;
PART_NUMBER"AL003126K08"
PART_TYPE"SMLF"
VALUE"74CBTLV3126PW"
MATERIAL"IC"
$LOCATION"U67"
CDS_LIB"pure_quanta"
NEEDS_NO_SIZE"TRUE"
CDS_LMAN_SYM_OUTLINE"-250,350,250,-350"
CDS_LOCATION"U67"
$SEC"1"
CDS_SEC"1";
"VCC"
$PN"14"2;
"4OE"
$PN"13"17;
"4A"
$PN"12"30;
"4B"
$PN"11"58;
"3OE"
$PN"10"17;
"3A"
$PN"9"44;
"GND"
$PN"7"8;
"1A"
$PN"2"46;
"2B"
$PN"6"57;
"1B"
$PN"3"33;
"2OE"
$PN"4"17;
"1OE"
$PN"1"17;
"3B"
$PN"8"59;
"2A"
$PN"5"45;
%"Q_CAP"
"1","(-2375,6950)","2","pure_quanta","I40";
;
PART_NUMBER"CH4104K1B00"
VOLTAGE"25V"
VALUE"0.1UF"
MATERIAL"X7R"
PACK_TYPE"0402"
TOLERANCE"10%"
$LOCATION"C640"
CDS_LIB"pure_quanta"
CDS_LOCATION"C640"
$SEC"1"
CDS_SEC"1";
"B"
$PN"2"7;
"A"
$PN"1"2;
%"UNIVERSAL_GND"
"1","(-2375,6725)","0","logical_power","I41";
;
CDS_LIB"logical_power"
HDL_POWER"GND";
"A"7;
%"UNIVERSAL_POWER"
"1","(-2175,7275)","0","logical_power","I42";
;
HDL_POWER"P3V3_AUX"
CDS_LIB"logical_power";
"A"2;
%"Q_RES"
"2","(475,1825)","0","pure_quanta","I43";
;
PART_NUMBER"CS11002FB07"
PACK_TYPE"0402LF"
WATTAGE"1/16W"
MATERIAL"CHIP"
TOLERANCE"1%"
VALUE"100"
$LOCATION"R1896"
CDS_LIB"pure_quanta"
CDS_LOCATION"R1896"
$SEC"1"
CDS_SEC"1";
"A"
$PN"1"55;
"B"
$PN"2"6;
%"Q_RES"
"1","(-4675,3675)","0","pure_quanta","I5";
;
PART_NUMBER"CS03322FB03"
PACK_TYPE"0402LF"
WATTAGE"1/16W"
VALUE"33.2"
TOLERANCE"1%"
MATERIAL"CHIP"
$LOCATION"R1719"
CDS_LIB"pure_quanta"
CDS_LOCATION"R1719"
$SEC"1"
CDS_SEC"1";
"B"
$PN"2"22;
"A"
$PN"1"21;
%"Q_RES"
"2","(725,1825)","0","pure_quanta","I50";
;
PART_NUMBER"CS11002FB07"
WATTAGE"1/16W"
TOLERANCE"1%"
VALUE"100"
MATERIAL"CHIP"
PACK_TYPE"0402LF"
$LOCATION"R1897"
CDS_LIB"pure_quanta"
CDS_LOCATION"R1897"
$SEC"1"
CDS_SEC"1";
"A"
$PN"1"49;
"B"
$PN"2"6;
%"UNIVERSAL_GND"
"1","(975,1550)","0","logical_power","I51";
;
HDL_POWER"GND"
CDS_LIB"logical_power";
"A"6;
%"Q_RES"
"2","(975,1825)","0","pure_quanta","I52";
;
PART_NUMBER"CS11002FB07"
PACK_TYPE"0402LF"
MATERIAL"CHIP"
WATTAGE"1/16W"
VALUE"100"
TOLERANCE"1%"
$LOCATION"R1898"
CDS_LIB"pure_quanta"
CDS_LOCATION"R1898"
$SEC"1"
CDS_SEC"1";
"A"
$PN"1"50;
"B"
$PN"2"6;
%"Q_RES"
"1","(1625,3275)","0","pure_quanta","I53";
;
PART_NUMBER"CS21002FB06"
PACK_TYPE"0402LF"
TOLERANCE"1%"
WATTAGE"1/16W"
VALUE"1K"
MATERIAL"CHIP"
$LOCATION"R1356"
CDS_LIB"pure_quanta"
CDS_LOCATION"R1356"
$SEC"1"
CDS_SEC"1";
"B"
$PN"2"5;
"A"
$PN"1"54;
%"Q_RES"
"1","(1625,3450)","0","pure_quanta","I54";
;
PART_NUMBER"CS41002FB09"
MATERIAL"CHIP"
VALUE"100K"
TOLERANCE"1%"
$LOCATION"R1355"
PACK_TYPE"0402LF"
WATTAGE"1/16W"
CDS_LIB"pure_quanta"
CDS_LOCATION"R1355"
$SEC"1"
CDS_SEC"1";
"B"
$PN"2"5;
"A"
$PN"1"52;
%"Q_RES"
"1","(1625,3600)","0","pure_quanta","I55";
;
PART_NUMBER"CS41002FB09"
MATERIAL"CHIP"
TOLERANCE"1%"
VALUE"100K"
$LOCATION"R1354"
PACK_TYPE"0402LF"
WATTAGE"1/16W"
CDS_LIB"pure_quanta"
CDS_LOCATION"R1354"
$SEC"1"
CDS_SEC"1";
"B"
$PN"2"5;
"A"
$PN"1"53;
%"Q_RES"
"1","(1625,3750)","0","pure_quanta","I56";
;
PART_NUMBER"CS41002FB09"
MATERIAL"CHIP"
TOLERANCE"1%"
VALUE"100K"
$LOCATION"R1353"
CDS_LIB"pure_quanta"
WATTAGE"1/16W"
PACK_TYPE"0402LF"
CDS_LOCATION"R1353"
$SEC"1"
CDS_SEC"1";
"B"
$PN"2"5;
"A"
$PN"1"51;
%"UNIVERSAL_GND"
"1","(-3750,2200)","0","logical_power","I6";
;
HDL_POWER"GND"
CDS_LIB"logical_power";
"A"15;
%"UNIVERSAL_GND"
"1","(2225,3050)","0","logical_power","I60";
;
CDS_LIB"logical_power"
HDL_POWER"GND";
"A"5;
%"Q_RES"
"1","(50,4750)","0","pure_quanta","I61";
;
PART_NUMBER"CS00002JB13"
VALUE"0"
MATERIAL"CHIP"
$LOCATION"R1296"
TOLERANCE"5%"
WATTAGE"1/16W"
PACK_TYPE"0402LF"
CDS_LIB"pure_quanta"
CDS_LOCATION"R1296"
$SEC"1"
CDS_SEC"1";
"B"
$PN"2"38;
"A"
$PN"1"31;
%"Q_RES"
"1","(50,4900)","0","pure_quanta","I65";
;
PART_NUMBER"CS00002JB13"
MATERIAL"CHIP"
VALUE"0"
$LOCATION"R1295"
TOLERANCE"5%"
WATTAGE"1/16W"
PACK_TYPE"0402LF"
CDS_LIB"pure_quanta"
CDS_LOCATION"R1295"
$SEC"1"
CDS_SEC"1";
"B"
$PN"2"28;
"A"
$PN"1"47;
%"Q_RES"
"1","(50,5050)","0","pure_quanta","I66";
;
PART_NUMBER"CS00002JB13"
VALUE"0"
MATERIAL"CHIP"
$LOCATION"R1294"
TOLERANCE"5%"
CDS_LIB"pure_quanta"
PACK_TYPE"0402LF"
WATTAGE"1/16W"
CDS_LOCATION"R1294"
$SEC"1"
CDS_SEC"1";
"B"
$PN"2"37;
"A"
$PN"1"48;
%"Q_RES"
"1","(50,6175)","0","pure_quanta","I67";
;
PART_NUMBER"CS02202FB02"
VALUE"22"
MATERIAL"CHIP"
$LOCATION"R1293"
WATTAGE"1/16W"
TOLERANCE"1%"
PACK_TYPE"0402LF"
CDS_LIB"pure_quanta"
CDS_LOCATION"R1293"
$SEC"1"
CDS_SEC"1";
"B"
$PN"2"43;
"A"
$PN"1"46;
%"Q_RES"
"1","(50,6325)","0","pure_quanta","I68";
;
PART_NUMBER"CS02202FB02"
MATERIAL"CHIP"
VALUE"22"
$LOCATION"R1292"
WATTAGE"1/16W"
TOLERANCE"1%"
PACK_TYPE"0402LF"
CDS_LIB"pure_quanta"
CDS_LOCATION"R1292"
$SEC"1"
CDS_SEC"1";
"B"
$PN"2"42;
"A"
$PN"1"45;
%"Q_RES"
"1","(50,6475)","0","pure_quanta","I69";
;
PART_NUMBER"CS02202FB02"
VALUE"22"
MATERIAL"CHIP"
$LOCATION"R1291"
CDS_LIB"pure_quanta"
PACK_TYPE"0402LF"
TOLERANCE"1%"
WATTAGE"1/16W"
CDS_LOCATION"R1291"
$SEC"1"
CDS_SEC"1";
"B"
$PN"2"26;
"A"
$PN"1"44;
%"74LVC1G126SE7"
"1","(-3375,2000)","0","pure_quanta","I7";
;
PART_NUMBER"AL1G0126009"
VALUE"74LVC1G126SE-7"
PART_TYPE"SMLF"
MATERIAL"IC"
LOCATION"U224"
NEEDS_NO_SIZE"TRUE"
CDS_LMAN_SYM_OUTLINE"-100,100,100,-100"
CDS_LIB"pure_quanta"
$SEC"1"
CDS_SEC"1";
"OE"
$PN"1"19;
"GND"
$PN"3"14;
"VCC"
$PN"5"1;
"Y"
$PN"4"35;
"A"
$PN"2"36;
%"Q_RES"
"1","(1625,3900)","0","pure_quanta","I71";
;
PART_NUMBER"CS41002FB09"
VALUE"100K"
MATERIAL"CHIP"
TOLERANCE"1%"
$LOCATION"R1352"
PACK_TYPE"0402LF"
WATTAGE"1/16W"
CDS_LIB"pure_quanta"
CDS_LOCATION"R1352"
$SEC"1"
CDS_SEC"1";
"B"
$PN"2"5;
"A"
$PN"1"39;
%"Q_RES"
"1","(1625,4050)","0","pure_quanta","I72";
;
PART_NUMBER"CS41002FB09"
TOLERANCE"1%"
MATERIAL"CHIP"
VALUE"100K"
$LOCATION"R1351"
PACK_TYPE"0402LF"
WATTAGE"1/16W"
CDS_LIB"pure_quanta"
CDS_LOCATION"R1351"
$SEC"1"
CDS_SEC"1";
"B"
$PN"2"5;
"A"
$PN"1"41;
%"Q_RES"
"1","(1625,4200)","0","pure_quanta","I73";
;
PART_NUMBER"CS41002FB09"
VALUE"100K"
WATTAGE"1/16W"
MATERIAL"CHIP"
TOLERANCE"1%"
PACK_TYPE"0402LF"
$LOCATION"R1350"
CDS_LIB"pure_quanta"
CDS_LOCATION"R1350"
$SEC"1"
CDS_SEC"1";
"B"
$PN"2"5;
"A"
$PN"1"40;
%"Q_CAP"
"1","(-3750,2425)","2","pure_quanta","I8";
;
PART_NUMBER"CH4104K1B00"
TOLERANCE"10%"
PACK_TYPE"0402"
VOLTAGE"25V"
MATERIAL"X7R"
VALUE"0.1UF"
$LOCATION"C1840"
CDS_LIB"pure_quanta"
CDS_LOCATION"C1840"
$SEC"1"
CDS_SEC"1";
"B"
$PN"2"15;
"A"
$PN"1"1;
%"Q_RES"
"1","(1500,6450)","1","pure_quanta","I80";
;
PART_NUMBER"CS00002JB13"
MATERIAL"CHIP"
VALUE"0"
$LOCATION"R3237"
CDS_LIB"pure_quanta"
WATTAGE"1/16W"
PACK_TYPE"0402LF"
TOLERANCE"5%"
CDS_LOCATION"R3237"
$SEC"1"
CDS_SEC"1";
"B"
$PN"2"30;
"A"
$PN"1"27;
%"Q_RES"
"1","(1650,6625)","0","pure_quanta","I81";
;
PART_NUMBER"CS02202FB02"
MATERIAL"EMPTY"
PACK_TYPE"0402LF"
VALUE"22"
WATTAGE"1/16W"
$LOCATION"R1290"
TOLERANCE"1%"
CDS_LIB"pure_quanta"
CDS_LOCATION"R1290"
$SEC"1"
CDS_SEC"1";
"B"
$PN"2"29;
"A"
$PN"1"30;
%"Q_RES"
"1","(-1825,3725)","0","pure_quanta","I83";
;
PART_NUMBER"CS04992FB07"
VALUE"49.9"
MATERIAL"CHIP"
LOCATION"R2473"
CDS_LIB"pure_quanta"
PACK_TYPE"0402LF"
TOLERANCE"1%"
WATTAGE"1/16W"
$SEC"1"
CDS_SEC"1";
"B"
$PN"2"17;
"A"
$PN"1"18;
%"UNIVERSAL_POWER"
"1","(-3750,2725)","0","logical_power","I9";
;
HDL_POWER"P3V3_AUX"
CDS_LIB"logical_power";
"A"1;
END.
